(kicad_pcb
	(version 20260206)
	(generator "pcbnew")
	(generator_version "10.0")
	(general
		(thickness 1.6)
		(legacy_teardrops no)
	)
	(paper "A4")
	(title_block
		(title "01162023_DA0F0TEBIF0_F0T_Expander_BD_F_brd_V02_OCP.brd")
		(comment 1 "Grand Teton / footprints 2186-2193 of 9728")
	)
	(layers
		(0 "F.Cu" signal "TOP")
		(4 "In1.Cu" signal "GND")
		(6 "In2.Cu" signal "VCC")
		(8 "In3.Cu" signal "VCC1")
		(10 "In4.Cu" signal "GND1")
		(12 "In5.Cu" signal "IN1")
		(14 "In6.Cu" signal "GND2")
		(16 "In7.Cu" signal "IN2")
		(18 "In8.Cu" signal "GND3")
		(20 "In9.Cu" signal "IN3")
		(22 "In10.Cu" signal "GND4")
		(24 "In11.Cu" signal "IN4")
		(26 "In12.Cu" signal "GND5")
		(28 "In13.Cu" signal "IN5")
		(30 "In14.Cu" signal "GND6")
		(32 "In15.Cu" signal "IN6")
		(34 "In16.Cu" signal "GND7")
		(2 "B.Cu" signal "BOTTOM")
		(9 "F.Adhes" user "F.Adhesive")
		(11 "B.Adhes" user "B.Adhesive")
		(13 "F.Paste" user "Package Geometry/Pastemask Top")
		(15 "B.Paste" user "Package Geometry/Pastemask Bottom")
		(5 "F.SilkS" user "Ref Des/Silkscreen Top")
		(7 "B.SilkS" user "Ref Des/Silkscreen Bottom")
		(1 "F.Mask" user "Board Geometry/Soldermask Top")
		(3 "B.Mask" user "Board Geometry/Soldermask Bottom")
		(17 "Dwgs.User" user "User.Drawings")
		(19 "Cmts.User" user "User.Comments")
		(21 "Eco1.User" user "User.Eco1")
		(23 "Eco2.User" user "User.Eco2")
		(25 "Edge.Cuts" user "Board Geometry/Outline")
		(27 "Margin" user)
		(31 "F.CrtYd" user "Package Geometry/Place Bound Top")
		(29 "B.CrtYd" user "Package Geometry/Place Bound Bottom")
		(35 "F.Fab" user "Ref Des/Assembly Top")
		(33 "B.Fab" user "Ref Des/Assembly Bottom")
	)
	(footprint ""
		(layer "F.Cu")
		(at 204.430376 -364.885986 180)
		(property "Reference" "R6600"
			(at 0 0 180)
			(layer "F.SilkS")
			(hide yes)
			(effects
				(font
					(size 1.27 1.27)
				)
			)
		)
		(property "Value" ""
			(at 0 0 180)
			(layer "F.Fab")
			(effects
				(font
					(size 1.27 1.27)
				)
			)
		)
		(duplicate_pad_numbers_are_jumpers no)
		(fp_line
			(start 0.7874 0.4064)
			(end -0.7874 0.4064)
			(stroke
				(width 0.1524)
				(type default)
			)
			(layer "F.SilkS")
		)
		(fp_line
			(start 0.7874 -0.4064)
			(end 0.7874 0.4064)
			(stroke
				(width 0.1524)
				(type default)
			)
			(layer "F.SilkS")
		)
		(fp_line
			(start -0.7874 0.4064)
			(end -0.7874 -0.4064)
			(stroke
				(width 0.1524)
				(type default)
			)
			(layer "F.SilkS")
		)
		(fp_line
			(start -0.7874 -0.4064)
			(end 0.7874 -0.4064)
			(stroke
				(width 0.1524)
				(type default)
			)
			(layer "F.SilkS")
		)
		(fp_line
			(start 0.67945 0.3048)
			(end 0.120396 0.3048)
			(stroke
				(width 0.1)
				(type default)
			)
			(layer "F.Fab")
		)
		(fp_line
			(start 0.67945 -0.3048)
			(end 0.67945 0.3048)
			(stroke
				(width 0.1)
				(type default)
			)
			(layer "F.Fab")
		)
		(fp_line
			(start 0.12065 -0.2794)
			(end 0.12065 -0.3048)
			(stroke
				(width 0.1)
				(type default)
			)
			(layer "F.Fab")
		)
		(fp_line
			(start 0.12065 -0.3048)
			(end 0.67945 -0.3048)
			(stroke
				(width 0.1)
				(type default)
			)
			(layer "F.Fab")
		)
		(fp_line
			(start 0.120396 0.3048)
			(end 0.120396 0.2794)
			(stroke
				(width 0.1)
				(type default)
			)
			(layer "F.Fab")
		)
		(fp_line
			(start 0.120396 0.2794)
			(end -0.12065 0.2794)
			(stroke
				(width 0.1)
				(type default)
			)
			(layer "F.Fab")
		)
		(fp_line
			(start -0.12065 0.3048)
			(end -0.67945 0.3048)
			(stroke
				(width 0.1)
				(type default)
			)
			(layer "F.Fab")
		)
		(fp_line
			(start -0.12065 0.2794)
			(end -0.12065 0.3048)
			(stroke
				(width 0.1)
				(type default)
			)
			(layer "F.Fab")
		)
		(fp_line
			(start -0.12065 -0.2794)
			(end 0.12065 -0.2794)
			(stroke
				(width 0.1)
				(type default)
			)
			(layer "F.Fab")
		)
		(fp_line
			(start -0.12065 -0.305054)
			(end -0.12065 -0.2794)
			(stroke
				(width 0.1)
				(type default)
			)
			(layer "F.Fab")
		)
		(fp_line
			(start -0.67945 0.3048)
			(end -0.67945 -0.305054)
			(stroke
				(width 0.1)
				(type default)
			)
			(layer "F.Fab")
		)
		(fp_line
			(start -0.67945 -0.305054)
			(end -0.12065 -0.305054)
			(stroke
				(width 0.1)
				(type default)
			)
			(layer "F.Fab")
		)
		(pad "1" smd circle
			(at -0.40005 0 180)
			(size 0 0)
			(layers "F.Cu" "F.Mask" "F.Paste")
			(net "HSC_P12V_EN")
		)
		(pad "2" smd circle
			(at 0.40005 0 180)
			(size 0 0)
			(layers "F.Cu" "F.Mask" "F.Paste")
			(net "HSC_P12V_MP5990_EN")
		)
	)
	(footprint ""
		(layer "F.Cu")
		(at 343.514172 -271.703546 -90)
		(property "Reference" "PC144"
			(at 0 0 270)
			(layer "F.SilkS")
			(hide yes)
			(effects
				(font
					(size 1.27 1.27)
				)
			)
		)
		(property "Value" ""
			(at 0 0 270)
			(layer "F.Fab")
			(effects
				(font
					(size 1.27 1.27)
				)
			)
		)
		(duplicate_pad_numbers_are_jumpers no)
		(fp_line
			(start -2.146046 3.400044)
			(end -3.400044 2.146046)
			(stroke
				(width 0.1524)
				(type default)
			)
			(layer "F.SilkS")
		)
		(fp_line
			(start 3.400044 3.400044)
			(end -2.146046 3.400044)
			(stroke
				(width 0.1524)
				(type default)
			)
			(layer "F.SilkS")
		)
		(fp_line
			(start -3.400044 2.146046)
			(end -3.400044 0.9398)
			(stroke
				(width 0.1524)
				(type default)
			)
			(layer "F.SilkS")
		)
		(fp_line
			(start 3.400044 0.9398)
			(end 3.400044 3.400044)
			(stroke
				(width 0.1524)
				(type default)
			)
			(layer "F.SilkS")
		)
		(fp_line
			(start 3.400044 -0.9398)
			(end 3.400044 -3.400044)
			(stroke
				(width 0.1524)
				(type default)
			)
			(layer "F.SilkS")
		)
		(fp_line
			(start -3.400044 -2.146046)
			(end -3.400044 -0.9398)
			(stroke
				(width 0.1524)
				(type default)
			)
			(layer "F.SilkS")
		)
		(fp_line
			(start -2.146046 -3.400044)
			(end -3.400044 -2.146046)
			(stroke
				(width 0.1524)
				(type default)
			)
			(layer "F.SilkS")
		)
		(fp_line
			(start 3.400044 -3.400044)
			(end -2.146046 -3.400044)
			(stroke
				(width 0.1524)
				(type default)
			)
			(layer "F.SilkS")
		)
		(fp_line
			(start -3.400044 3.400044)
			(end 3.400044 3.400044)
			(stroke
				(width 0.1)
				(type default)
			)
			(layer "F.Fab")
		)
		(fp_line
			(start 3.400044 3.400044)
			(end 3.400044 -3.400044)
			(stroke
				(width 0.1)
				(type default)
			)
			(layer "F.Fab")
		)
		(fp_line
			(start -3.400044 -3.400044)
			(end -3.400044 3.400044)
			(stroke
				(width 0.1)
				(type default)
			)
			(layer "F.Fab")
		)
		(fp_line
			(start 3.400044 -3.400044)
			(end -3.400044 -3.400044)
			(stroke
				(width 0.1)
				(type default)
			)
			(layer "F.Fab")
		)
		(pad "1" smd rect
			(at -2.70002 0 180)
			(size 1.6002 3.5052)
			(layers "F.Cu" "F.Mask" "F.Paste")
			(net "SW_P12V_P0V8_PEX2_FLT")
		)
		(pad "2" smd rect
			(at 2.70002 0 180)
			(size 1.6002 3.5052)
			(layers "F.Cu" "F.Mask" "F.Paste")
			(net "GND")
		)
	)
	(footprint ""
		(layer "F.Cu")
		(at 338.074 -162.814)
		(property "Reference" "R4810"
			(at 0 0 0)
			(layer "F.SilkS")
			(hide yes)
			(effects
				(font
					(size 1.27 1.27)
				)
			)
		)
		(property "Value" ""
			(at 0 0 0)
			(layer "F.Fab")
			(effects
				(font
					(size 1.27 1.27)
				)
			)
		)
		(duplicate_pad_numbers_are_jumpers no)
		(fp_line
			(start -0.7874 -0.4064)
			(end 0.7874 -0.4064)
			(stroke
				(width 0.1524)
				(type default)
			)
			(layer "F.SilkS")
		)
		(fp_line
			(start -0.7874 0.4064)
			(end -0.7874 -0.4064)
			(stroke
				(width 0.1524)
				(type default)
			)
			(layer "F.SilkS")
		)
		(fp_line
			(start 0.7874 -0.4064)
			(end 0.7874 0.4064)
			(stroke
				(width 0.1524)
				(type default)
			)
			(layer "F.SilkS")
		)
		(fp_line
			(start 0.7874 0.4064)
			(end -0.7874 0.4064)
			(stroke
				(width 0.1524)
				(type default)
			)
			(layer "F.SilkS")
		)
		(fp_line
			(start -0.67945 -0.305054)
			(end -0.12065 -0.305054)
			(stroke
				(width 0.1)
				(type default)
			)
			(layer "F.Fab")
		)
		(fp_line
			(start -0.67945 0.3048)
			(end -0.67945 -0.305054)
			(stroke
				(width 0.1)
				(type default)
			)
			(layer "F.Fab")
		)
		(fp_line
			(start -0.12065 -0.305054)
			(end -0.12065 -0.2794)
			(stroke
				(width 0.1)
				(type default)
			)
			(layer "F.Fab")
		)
		(fp_line
			(start -0.12065 -0.2794)
			(end 0.12065 -0.2794)
			(stroke
				(width 0.1)
				(type default)
			)
			(layer "F.Fab")
		)
		(fp_line
			(start -0.12065 0.2794)
			(end -0.12065 0.3048)
			(stroke
				(width 0.1)
				(type default)
			)
			(layer "F.Fab")
		)
		(fp_line
			(start -0.12065 0.3048)
			(end -0.67945 0.3048)
			(stroke
				(width 0.1)
				(type default)
			)
			(layer "F.Fab")
		)
		(fp_line
			(start 0.120396 0.2794)
			(end -0.12065 0.2794)
			(stroke
				(width 0.1)
				(type default)
			)
			(layer "F.Fab")
		)
		(fp_line
			(start 0.120396 0.3048)
			(end 0.120396 0.2794)
			(stroke
				(width 0.1)
				(type default)
			)
			(layer "F.Fab")
		)
		(fp_line
			(start 0.12065 -0.3048)
			(end 0.67945 -0.3048)
			(stroke
				(width 0.1)
				(type default)
			)
			(layer "F.Fab")
		)
		(fp_line
			(start 0.12065 -0.2794)
			(end 0.12065 -0.3048)
			(stroke
				(width 0.1)
				(type default)
			)
			(layer "F.Fab")
		)
		(fp_line
			(start 0.67945 -0.3048)
			(end 0.67945 0.3048)
			(stroke
				(width 0.1)
				(type default)
			)
			(layer "F.Fab")
		)
		(fp_line
			(start 0.67945 0.3048)
			(end 0.120396 0.3048)
			(stroke
				(width 0.1)
				(type default)
			)
			(layer "F.Fab")
		)
		(pad "1" smd circle
			(at -0.40005 0)
			(size 0 0)
			(layers "F.Cu" "F.Mask" "F.Paste")
			(net "PEX3_PCA9555_0_INT_N")
		)
		(pad "2" smd circle
			(at 0.40005 0)
			(size 0 0)
			(layers "F.Cu" "F.Mask" "F.Paste")
			(net "P1V8_PEX")
		)
	)
	(footprint ""
		(layer "F.Cu")
		(at 72.51446 -66.32194 90)
		(property "Reference" "R5844"
			(at 0 0 90)
			(layer "F.SilkS")
			(hide yes)
			(effects
				(font
					(size 1.27 1.27)
				)
			)
		)
		(property "Value" ""
			(at 0 0 90)
			(layer "F.Fab")
			(effects
				(font
					(size 1.27 1.27)
				)
			)
		)
		(duplicate_pad_numbers_are_jumpers no)
		(fp_line
			(start 0.7874 -0.4064)
			(end 0.7874 0.4064)
			(stroke
				(width 0.1524)
				(type default)
			)
			(layer "F.SilkS")
		)
		(fp_line
			(start -0.7874 -0.4064)
			(end 0.7874 -0.4064)
			(stroke
				(width 0.1524)
				(type default)
			)
			(layer "F.SilkS")
		)
		(fp_line
			(start 0.7874 0.4064)
			(end -0.7874 0.4064)
			(stroke
				(width 0.1524)
				(type default)
			)
			(layer "F.SilkS")
		)
		(fp_line
			(start -0.7874 0.4064)
			(end -0.7874 -0.4064)
			(stroke
				(width 0.1524)
				(type default)
			)
			(layer "F.SilkS")
		)
		(fp_line
			(start -0.12065 -0.305054)
			(end -0.12065 -0.2794)
			(stroke
				(width 0.1)
				(type default)
			)
			(layer "F.Fab")
		)
		(fp_line
			(start -0.67945 -0.305054)
			(end -0.12065 -0.305054)
			(stroke
				(width 0.1)
				(type default)
			)
			(layer "F.Fab")
		)
		(fp_line
			(start 0.67945 -0.3048)
			(end 0.67945 0.3048)
			(stroke
				(width 0.1)
				(type default)
			)
			(layer "F.Fab")
		)
		(fp_line
			(start 0.12065 -0.3048)
			(end 0.67945 -0.3048)
			(stroke
				(width 0.1)
				(type default)
			)
			(layer "F.Fab")
		)
		(fp_line
			(start 0.12065 -0.2794)
			(end 0.12065 -0.3048)
			(stroke
				(width 0.1)
				(type default)
			)
			(layer "F.Fab")
		)
		(fp_line
			(start -0.12065 -0.2794)
			(end 0.12065 -0.2794)
			(stroke
				(width 0.1)
				(type default)
			)
			(layer "F.Fab")
		)
		(fp_line
			(start 0.120396 0.2794)
			(end -0.12065 0.2794)
			(stroke
				(width 0.1)
				(type default)
			)
			(layer "F.Fab")
		)
		(fp_line
			(start -0.12065 0.2794)
			(end -0.12065 0.3048)
			(stroke
				(width 0.1)
				(type default)
			)
			(layer "F.Fab")
		)
		(fp_line
			(start 0.67945 0.3048)
			(end 0.120396 0.3048)
			(stroke
				(width 0.1)
				(type default)
			)
			(layer "F.Fab")
		)
		(fp_line
			(start 0.120396 0.3048)
			(end 0.120396 0.2794)
			(stroke
				(width 0.1)
				(type default)
			)
			(layer "F.Fab")
		)
		(fp_line
			(start -0.12065 0.3048)
			(end -0.67945 0.3048)
			(stroke
				(width 0.1)
				(type default)
			)
			(layer "F.Fab")
		)
		(fp_line
			(start -0.67945 0.3048)
			(end -0.67945 -0.305054)
			(stroke
				(width 0.1)
				(type default)
			)
			(layer "F.Fab")
		)
		(pad "1" smd circle
			(at -0.40005 0 90)
			(size 0 0)
			(layers "F.Cu" "F.Mask" "F.Paste")
			(net "SSD2_PWR_EN_R")
		)
		(pad "2" smd circle
			(at 0.40005 0 90)
			(size 0 0)
			(layers "F.Cu" "F.Mask" "F.Paste")
			(net "P12V_SSD2_CO_EN")
		)
	)
	(footprint ""
		(layer "F.Cu")
		(at 437.778906 -308.323488 135)
		(property "Reference" "R1457"
			(at 0 0 135)
			(layer "F.SilkS")
			(hide yes)
			(effects
				(font
					(size 1.27 1.27)
				)
			)
		)
		(property "Value" ""
			(at 0 0 135)
			(layer "F.Fab")
			(effects
				(font
					(size 1.27 1.27)
				)
			)
		)
		(duplicate_pad_numbers_are_jumpers no)
		(fp_line
			(start 0.787389 -0.406267)
			(end 0.787389 0.406267)
			(stroke
				(width 0.1524)
				(type default)
			)
			(layer "F.SilkS")
		)
		(fp_line
			(start 0.787389 0.406267)
			(end -0.787389 0.406267)
			(stroke
				(width 0.1524)
				(type default)
			)
			(layer "F.SilkS")
		)
		(fp_line
			(start -0.787389 -0.406267)
			(end 0.787389 -0.406267)
			(stroke
				(width 0.1524)
				(type default)
			)
			(layer "F.SilkS")
		)
		(fp_line
			(start -0.787389 0.406267)
			(end -0.787389 -0.406267)
			(stroke
				(width 0.1524)
				(type default)
			)
			(layer "F.SilkS")
		)
		(fp_line
			(start 0.679446 -0.30479)
			(end 0.679446 0.30479)
			(stroke
				(width 0.1)
				(type default)
			)
			(layer "F.Fab")
		)
		(fp_line
			(start 0.120515 -0.30479)
			(end 0.679446 -0.30479)
			(stroke
				(width 0.1)
				(type default)
			)
			(layer "F.Fab")
		)
		(fp_line
			(start 0.120695 -0.279466)
			(end 0.120515 -0.30479)
			(stroke
				(width 0.1)
				(type default)
			)
			(layer "F.Fab")
		)
		(fp_line
			(start 0.679446 0.30479)
			(end 0.120515 0.30479)
			(stroke
				(width 0.1)
				(type default)
			)
			(layer "F.Fab")
		)
		(fp_line
			(start -0.120695 -0.304969)
			(end -0.120695 -0.279466)
			(stroke
				(width 0.1)
				(type default)
			)
			(layer "F.Fab")
		)
		(fp_line
			(start -0.120695 -0.279466)
			(end 0.120695 -0.279466)
			(stroke
				(width 0.1)
				(type default)
			)
			(layer "F.Fab")
		)
		(fp_line
			(start 0.120335 0.279466)
			(end -0.120695 0.279466)
			(stroke
				(width 0.1)
				(type default)
			)
			(layer "F.Fab")
		)
		(fp_line
			(start 0.120515 0.30479)
			(end 0.120335 0.279466)
			(stroke
				(width 0.1)
				(type default)
			)
			(layer "F.Fab")
		)
		(fp_line
			(start -0.679446 -0.305149)
			(end -0.120695 -0.304969)
			(stroke
				(width 0.1)
				(type default)
			)
			(layer "F.Fab")
		)
		(fp_line
			(start -0.120695 0.279466)
			(end -0.120515 0.30479)
			(stroke
				(width 0.1)
				(type default)
			)
			(layer "F.Fab")
		)
		(fp_line
			(start -0.120515 0.30479)
			(end -0.679446 0.30479)
			(stroke
				(width 0.1)
				(type default)
			)
			(layer "F.Fab")
		)
		(fp_line
			(start -0.679446 0.30479)
			(end -0.679446 -0.305149)
			(stroke
				(width 0.1)
				(type default)
			)
			(layer "F.Fab")
		)
		(pad "1" smd circle
			(at -0.40005 0 135)
			(size 0 0)
			(layers "F.Cu" "F.Mask" "F.Paste")
			(net "GND")
		)
		(pad "2" smd circle
			(at 0.40005 0 135)
			(size 0 0)
			(layers "F.Cu" "F.Mask" "F.Paste")
			(net "PEX3_SPARE7")
		)
	)
	(footprint ""
		(layer "F.Cu")
		(at 434.141372 -343.952322 90)
		(property "Reference" "C802"
			(at 0 0 90)
			(layer "F.SilkS")
			(hide yes)
			(effects
				(font
					(size 1.27 1.27)
				)
			)
		)
		(property "Value" ""
			(at 0 0 90)
			(layer "F.Fab")
			(effects
				(font
					(size 1.27 1.27)
				)
			)
		)
		(duplicate_pad_numbers_are_jumpers no)
		(fp_line
			(start 0.299974 -0.150114)
			(end 0.299974 0.150114)
			(stroke
				(width 0.1)
				(type default)
			)
			(layer "F.Fab")
		)
		(fp_line
			(start -0.299974 -0.150114)
			(end 0.299974 -0.150114)
			(stroke
				(width 0.1)
				(type default)
			)
			(layer "F.Fab")
		)
		(fp_line
			(start 0.299974 0.150114)
			(end -0.299974 0.150114)
			(stroke
				(width 0.1)
				(type default)
			)
			(layer "F.Fab")
		)
		(fp_line
			(start -0.299974 0.150114)
			(end -0.299974 -0.150114)
			(stroke
				(width 0.1)
				(type default)
			)
			(layer "F.Fab")
		)
		(pad "1" smd rect
			(at -0.2667 0 90)
			(size 0.3048 0.381)
			(layers "F.Cu" "F.Mask" "F.Paste")
			(net "P5E_PEX3_STN7_TX_DP<123>")
		)
		(pad "2" smd rect
			(at 0.2667 0 90)
			(size 0.3048 0.381)
			(layers "F.Cu" "F.Mask" "F.Paste")
			(net "P5E_PEX3_STN7_TX_C_DP<123>")
		)
	)
	(footprint ""
		(layer "F.Cu")
		(at 287.439862 -356.244906 90)
		(property "Reference" "C2360"
			(at 0 0 90)
			(layer "F.SilkS")
			(hide yes)
			(effects
				(font
					(size 1.27 1.27)
				)
			)
		)
		(property "Value" ""
			(at 0 0 90)
			(layer "F.Fab")
			(effects
				(font
					(size 1.27 1.27)
				)
			)
		)
		(duplicate_pad_numbers_are_jumpers no)
		(fp_line
			(start 0.299974 -0.150114)
			(end 0.299974 0.150114)
			(stroke
				(width 0.1)
				(type default)
			)
			(layer "F.Fab")
		)
		(fp_line
			(start -0.299974 -0.150114)
			(end 0.299974 -0.150114)
			(stroke
				(width 0.1)
				(type default)
			)
			(layer "F.Fab")
		)
		(fp_line
			(start 0.299974 0.150114)
			(end -0.299974 0.150114)
			(stroke
				(width 0.1)
				(type default)
			)
			(layer "F.Fab")
		)
		(fp_line
			(start -0.299974 0.150114)
			(end -0.299974 -0.150114)
			(stroke
				(width 0.1)
				(type default)
			)
			(layer "F.Fab")
		)
		(pad "1" smd rect
			(at -0.2667 0 90)
			(size 0.3048 0.381)
			(layers "F.Cu" "F.Mask" "F.Paste")
			(net "P5E_PEX2_STN4_TX_DN<70>")
		)
		(pad "2" smd rect
			(at 0.2667 0 90)
			(size 0.3048 0.381)
			(layers "F.Cu" "F.Mask" "F.Paste")
			(net "P5E_PEX2_STN4_TX_C_DN<70>")
		)
	)
	(footprint ""
		(layer "F.Cu")
		(at 252.634496 -33.631886 180)
		(property "Reference" "C488"
			(at 0 0 180)
			(layer "F.SilkS")
			(hide yes)
			(effects
				(font
					(size 1.27 1.27)
				)
			)
		)
		(property "Value" ""
			(at 0 0 180)
			(layer "F.Fab")
			(effects
				(font
					(size 1.27 1.27)
				)
			)
		)
		(duplicate_pad_numbers_are_jumpers no)
		(fp_line
			(start 0.299974 0.150114)
			(end -0.299974 0.150114)
			(stroke
				(width 0.1)
				(type default)
			)
			(layer "F.Fab")
		)
		(fp_line
			(start 0.299974 -0.150114)
			(end 0.299974 0.150114)
			(stroke
				(width 0.1)
				(type default)
			)
			(layer "F.Fab")
		)
		(fp_line
			(start -0.299974 0.150114)
			(end -0.299974 -0.150114)
			(stroke
				(width 0.1)
				(type default)
			)
			(layer "F.Fab")
		)
		(fp_line
			(start -0.299974 -0.150114)
			(end 0.299974 -0.150114)
			(stroke
				(width 0.1)
				(type default)
			)
			(layer "F.Fab")
		)
		(pad "1" smd rect
			(at -0.2667 0 180)
			(size 0.3048 0.381)
			(layers "F.Cu" "F.Mask" "F.Paste")
			(net "P5E_PEX2_STN2_TX_DN<47>")
		)
		(pad "2" smd rect
			(at 0.2667 0 180)
			(size 0.3048 0.381)
			(layers "F.Cu" "F.Mask" "F.Paste")
			(net "P5E_PEX2_STN2_TX_C_DN<47>")
		)
	)
)
